(kicad_pcb
	(version 20241229)
	(generator "pcbnew")
	(generator_version "9.0")
	(general
		(thickness 1.294)
		(legacy_teardrops no)
	)
	(paper "A3")
	(title_block
		(title "Kintex 410T devboard")
		(date "2024-04-03")
		(rev "1.1.2")
		(comment 9 "footprints 818-822 of 975")
	)
	(layers
		(0 "F.Cu" mixed)
		(4 "In1.Cu" power)
		(6 "In2.Cu" power)
		(8 "In3.Cu" mixed)
		(10 "In4.Cu" power)
		(12 "In5.Cu" mixed)
		(14 "In6.Cu" power)
		(16 "In7.Cu" mixed)
		(18 "In8.Cu" power)
		(2 "B.Cu" mixed)
		(9 "F.Adhes" user "F.Adhesive")
		(11 "B.Adhes" user "B.Adhesive")
		(13 "F.Paste" user)
		(15 "B.Paste" user)
		(5 "F.SilkS" user "F.Silkscreen")
		(7 "B.SilkS" user "B.Silkscreen")
		(1 "F.Mask" user)
		(3 "B.Mask" user)
		(17 "Dwgs.User" user "User.Drawings")
		(19 "Cmts.User" user "User.Comments")
		(21 "Eco1.User" user "User.Eco1")
		(23 "Eco2.User" user "User.Eco2")
		(25 "Edge.Cuts" user)
		(27 "Margin" user)
		(31 "F.CrtYd" user "F.Courtyard")
		(29 "B.CrtYd" user "B.Courtyard")
		(35 "F.Fab" user)
		(33 "B.Fab" user)
	)
	(footprint "antmicro-footprints:R_Array_4x0201_Panasonic_EXB18V"
		(layer "B.Cu")
		(at 164.199999 146.199999 180)
		(property "Reference" "R16"
			(at 6.699999 -6.125001 0)
			(layer "B.SilkS")
			(effects
				(font
					(size 0.7 0.7)
					(thickness 0.15)
				)
				(justify right bottom mirror)
			)
		)
		(property "Value" "4x39R_0201_array"
			(at -1.1 -1.8 0)
			(layer "B.Fab")
			(effects
				(font
					(size 0.7 0.7)
					(thickness 0.15)
				)
				(justify left bottom mirror)
			)
		)
		(property "Description" "Fixed Network Resistor, 39 ohm, Isolated, 4 Resistors, 0502 [1406 Metric], Flat, ± 5%"
			(at 0 0 180)
			(layer "F.Fab")
			(hide yes)
			(effects
				(font
					(size 1.27 1.27)
					(thickness 0.15)
				)
			)
		)
		(property "Author" "Antmicro"
			(at 328.399998 292.399998 0)
			(layer "B.Fab")
			(hide yes)
			(effects
				(font
					(size 1 1)
					(thickness 0.15)
				)
				(justify mirror)
			)
		)
		(property "License" "Apache-2.0"
			(at 328.399998 292.399998 0)
			(layer "B.Fab")
			(hide yes)
			(effects
				(font
					(size 1 1)
					(thickness 0.15)
				)
				(justify mirror)
			)
		)
		(property "MPN" "EXB-18V390JX"
			(at 328.399998 292.399998 0)
			(layer "B.Fab")
			(hide yes)
			(effects
				(font
					(size 1 1)
					(thickness 0.15)
				)
				(justify mirror)
			)
		)
		(property "Manufacturer" "Panasonic"
			(at 328.399998 292.399998 0)
			(layer "B.Fab")
			(hide yes)
			(effects
				(font
					(size 1 1)
					(thickness 0.15)
				)
				(justify mirror)
			)
		)
		(property "Val" "4x39R_0201"
			(at 328.399998 292.399998 0)
			(layer "B.Fab")
			(hide yes)
			(effects
				(font
					(size 1 1)
					(thickness 0.15)
				)
				(justify mirror)
			)
		)
		(sheetname "DRAM + SRAM")
		(sheetfile "ram.kicad_sch")
		(attr smd)
		(fp_line
			(start 0.8 0.45)
			(end 0.8 -0.45)
			(stroke
				(width 0.12)
				(type solid)
			)
			(layer "B.SilkS")
		)
		(fp_line
			(start -0.8 0.45)
			(end -0.8 -0.45)
			(stroke
				(width 0.12)
				(type solid)
			)
			(layer "B.SilkS")
		)
		(fp_rect
			(start -0.898 0.66)
			(end 0.898 -0.65)
			(stroke
				(width 0.05)
				(type solid)
			)
			(fill no)
			(layer "B.CrtYd")
		)
		(pad "1" smd roundrect
			(at -0.6 -0.298 180)
			(size 0.2 0.4)
			(layers "B.Cu" "B.Mask" "B.Paste")
			(roundrect_rratio 0.25)
			(net 542 "/DRAM + SRAM/DDR.A11")
			(pinfunction "R1.1")
			(pintype "passive")
		)
		(pad "2" smd roundrect
			(at -0.202 -0.298 180)
			(size 0.2 0.4)
			(layers "B.Cu" "B.Mask" "B.Paste")
			(roundrect_rratio 0.25)
			(net 537 "/DRAM + SRAM/DDR.A6")
			(pinfunction "R2.1")
			(pintype "passive")
		)
		(pad "3" smd roundrect
			(at 0.2 -0.298 180)
			(size 0.2 0.4)
			(layers "B.Cu" "B.Mask" "B.Paste")
			(roundrect_rratio 0.25)
			(net 545 "/DRAM + SRAM/DDR.A14")
			(pinfunction "R3.1")
			(pintype "passive")
		)
		(pad "4" smd roundrect
			(at 0.598 -0.298 180)
			(size 0.2 0.4)
			(layers "B.Cu" "B.Mask" "B.Paste")
			(roundrect_rratio 0.25)
			(net 539 "/DRAM + SRAM/DDR.A8")
			(pinfunction "R4.1")
			(pintype "passive")
		)
		(pad "5" smd roundrect
			(at 0.598 0.3 180)
			(size 0.2 0.4)
			(layers "B.Cu" "B.Mask" "B.Paste")
			(roundrect_rratio 0.25)
			(net 7 "+0V675_VTT")
			(pinfunction "R4.2")
			(pintype "passive")
		)
		(pad "6" smd roundrect
			(at 0.2 0.3 180)
			(size 0.2 0.4)
			(layers "B.Cu" "B.Mask" "B.Paste")
			(roundrect_rratio 0.25)
			(net 7 "+0V675_VTT")
			(pinfunction "R3.2")
			(pintype "passive")
		)
		(pad "7" smd roundrect
			(at -0.202 0.3 180)
			(size 0.2 0.4)
			(layers "B.Cu" "B.Mask" "B.Paste")
			(roundrect_rratio 0.25)
			(net 7 "+0V675_VTT")
			(pinfunction "R2.2")
			(pintype "passive")
		)
		(pad "8" smd roundrect
			(at -0.6 0.3 180)
			(size 0.2 0.4)
			(layers "B.Cu" "B.Mask" "B.Paste")
			(roundrect_rratio 0.25)
			(net 7 "+0V675_VTT")
			(pinfunction "R1.2")
			(pintype "passive")
		)
	)
	(footprint "antmicro-footprints:C_0201"
		(layer "B.Cu")
		(at 191 116 -45)
		(descr "Capacitor SMD 0201")
		(tags "capacitor SMD 0201")
		(property "Reference" "C57"
			(at 1.202082 1.166726 315)
			(unlocked yes)
			(layer "B.SilkS")
			(effects
				(font
					(size 0.7 0.7)
					(thickness 0.15)
				)
				(justify left bottom mirror)
			)
		)
		(property "Value" "C_4u7_0201"
			(at 0 -1.399999 135)
			(layer "B.Fab")
			(effects
				(font
					(size 0.7 0.7)
					(thickness 0.15)
				)
				(justify left bottom mirror)
			)
		)
		(property "Description" "SMD Multilayer Ceramic Capacitor, 4.7 µF, 6.3 V, 0201 [0603 Metric], ± 20%, X5R, GRM Series"
			(at 0 0 315)
			(layer "F.Fab")
			(hide yes)
			(effects
				(font
					(size 1.27 1.27)
					(thickness 0.15)
				)
			)
		)
		(property "Author" "Antmicro"
			(at -26.081781 169.033008 0)
			(layer "B.Fab")
			(hide yes)
			(effects
				(font
					(size 1 1)
					(thickness 0.15)
				)
				(justify mirror)
			)
		)
		(property "Dielectric" ""
			(at -26.081781 169.033008 0)
			(layer "B.Fab")
			(hide yes)
			(effects
				(font
					(size 1 1)
					(thickness 0.15)
				)
				(justify mirror)
			)
		)
		(property "License" "Apache-2.0"
			(at -26.081781 169.033008 0)
			(layer "B.Fab")
			(hide yes)
			(effects
				(font
					(size 1 1)
					(thickness 0.15)
				)
				(justify mirror)
			)
		)
		(property "MPN" "GRM035R60J475ME15D"
			(at -26.081781 169.033008 0)
			(layer "B.Fab")
			(hide yes)
			(effects
				(font
					(size 1 1)
					(thickness 0.15)
				)
				(justify mirror)
			)
		)
		(property "Manufacturer" "Murata"
			(at -26.081781 169.033008 0)
			(layer "B.Fab")
			(hide yes)
			(effects
				(font
					(size 1 1)
					(thickness 0.15)
				)
				(justify mirror)
			)
		)
		(property "Val" "4u7"
			(at -26.081781 169.033008 0)
			(layer "B.Fab")
			(hide yes)
			(effects
				(font
					(size 1 1)
					(thickness 0.15)
				)
				(justify mirror)
			)
		)
		(property "Voltage" ""
			(at -26.081781 169.033008 0)
			(layer "B.Fab")
			(hide yes)
			(effects
				(font
					(size 1 1)
					(thickness 0.15)
				)
				(justify mirror)
			)
		)
		(sheetname "FPGA supply")
		(sheetfile "fpga-supply.kicad_sch")
		(attr smd)
		(fp_poly
			(pts
				(xy -0.7 0.35) (xy 0.7 0.35) (xy 0.7 -0.35) (xy -0.7 -0.35)
			)
			(stroke
				(width 0.05)
				(type default)
			)
			(fill no)
			(layer "B.CrtYd")
		)
		(fp_poly
			(pts
				(xy 0.3 -0.15) (xy -0.301 -0.15) (xy -0.301 0.149) (xy 0.3 0.149)
			)
			(stroke
				(width 0.15)
				(type solid)
			)
			(fill no)
			(layer "B.Fab")
		)
		(pad "" smd roundrect
			(at -0.349 0.002 315)
			(size 0.318 0.36)
			(layers "B.Paste")
			(roundrect_rratio 0.25)
		)
		(pad "" smd roundrect
			(at 0.341 0.002 315)
			(size 0.318 0.36)
			(layers "B.Paste")
			(roundrect_rratio 0.25)
		)
		(pad "1" smd roundrect
			(at -0.321 0.002 315)
			(size 0.46 0.4)
			(layers "B.Cu" "B.Mask")
			(roundrect_rratio 0.25)
			(net 1 "GND")
			(pintype "passive")
		)
		(pad "2" smd roundrect
			(at 0.32 0.002 315)
			(size 0.46 0.4)
			(layers "B.Cu" "B.Mask")
			(roundrect_rratio 0.25)
			(net 6 "+1V0_MGTAVCC")
			(pintype "passive")
		)
	)
	(footprint "antmicro-footprints:C_0402_1005Metric"
		(layer "B.Cu")
		(at 234.381 111.12 -90)
		(descr "Capacitor SMD 0402")
		(tags "capacitor SMD 0402")
		(property "Reference" "C212"
			(at -1.47 0.506 90)
			(layer "B.SilkS")
			(effects
				(font
					(size 0.7 0.7)
					(thickness 0.15)
				)
				(justify left bottom mirror)
			)
		)
		(property "Value" "C_100n_0402"
			(at 0 -1.4 90)
			(layer "B.Fab")
			(effects
				(font
					(size 0.7 0.7)
					(thickness 0.15)
				)
				(justify left bottom mirror)
			)
		)
		(property "Description" "SMD Multilayer Ceramic Capacitor, 0.1 µF, 50 V, 0402 [1005 Metric], ± 10%, X5R, GRM Series"
			(at 0 0 270)
			(layer "F.Fab")
			(hide yes)
			(effects
				(font
					(size 1.27 1.27)
					(thickness 0.15)
				)
			)
		)
		(property "Author" "Antmicro"
			(at 123.261 345.501 0)
			(layer "B.Fab")
			(hide yes)
			(effects
				(font
					(size 1 1)
					(thickness 0.15)
				)
				(justify mirror)
			)
		)
		(property "Dielectric" "X5R"
			(at 123.261 345.501 0)
			(layer "B.Fab")
			(hide yes)
			(effects
				(font
					(size 1 1)
					(thickness 0.15)
				)
				(justify mirror)
			)
		)
		(property "License" "Apache-2.0"
			(at 123.261 345.501 0)
			(layer "B.Fab")
			(hide yes)
			(effects
				(font
					(size 1 1)
					(thickness 0.15)
				)
				(justify mirror)
			)
		)
		(property "MPN" "GRM155R61H104KE14D"
			(at 123.261 345.501 0)
			(layer "B.Fab")
			(hide yes)
			(effects
				(font
					(size 1 1)
					(thickness 0.15)
				)
				(justify mirror)
			)
		)
		(property "Manufacturer" "Murata"
			(at 123.261 345.501 0)
			(layer "B.Fab")
			(hide yes)
			(effects
				(font
					(size 1 1)
					(thickness 0.15)
				)
				(justify mirror)
			)
		)
		(property "Val" "100n"
			(at 123.261 345.501 0)
			(layer "B.Fab")
			(hide yes)
			(effects
				(font
					(size 1 1)
					(thickness 0.15)
				)
				(justify mirror)
			)
		)
		(property "Voltage" "50V"
			(at 123.261 345.501 0)
			(layer "B.Fab")
			(hide yes)
			(effects
				(font
					(size 1 1)
					(thickness 0.15)
				)
				(justify mirror)
			)
		)
		(sheetname "SPI Flash + SD Card")
		(sheetfile "spi-flash.kicad_sch")
		(attr smd)
		(fp_rect
			(start -0.925 0.47)
			(end 0.925 -0.47)
			(stroke
				(width 0.05)
				(type default)
			)
			(fill no)
			(layer "B.CrtYd")
		)
		(fp_line
			(start -0.494 0.25)
			(end 0.504 0.25)
			(stroke
				(width 0.15)
				(type solid)
			)
			(layer "B.Fab")
		)
		(fp_line
			(start 0.504 0.25)
			(end 0.504 -0.248)
			(stroke
				(width 0.15)
				(type solid)
			)
			(layer "B.Fab")
		)
		(fp_line
			(start -0.494 -0.248)
			(end -0.494 0.25)
			(stroke
				(width 0.15)
				(type solid)
			)
			(layer "B.Fab")
		)
		(fp_line
			(start 0.504 -0.248)
			(end -0.494 -0.248)
			(stroke
				(width 0.15)
				(type solid)
			)
			(layer "B.Fab")
		)
		(pad "1" smd roundrect
			(at -0.48 0 270)
			(size 0.59 0.64)
			(layers "B.Cu" "B.Mask" "B.Paste")
			(roundrect_rratio 0.25)
			(net 1 "GND")
			(pintype "passive")
		)
		(pad "2" smd roundrect
			(at 0.48 0 270)
			(size 0.59 0.64)
			(layers "B.Cu" "B.Mask" "B.Paste")
			(roundrect_rratio 0.25)
			(net 3 "VCC_USR_B")
			(pintype "passive")
		)
	)
	(footprint "antmicro-footprints:NetTie-2_SMD_Pad0.127mm"
		(layer "B.Cu")
		(at 190.090001 112.88 180)
		(descr "Net tie, 2 pin, 0.127mm  SMD pads")
		(tags "net tie")
		(property "Reference" "NT34"
			(at -0.128 1.345 0)
			(layer "B.SilkS")
			(hide yes)
			(effects
				(font
					(size 0.7 0.7)
					(thickness 0.15)
				)
				(justify left bottom mirror)
			)
		)
		(property "Value" "Net-Tie_2"
			(at 0 -1.199 0)
			(layer "B.Fab")
			(effects
				(font
					(size 0.7 0.7)
					(thickness 0.15)
				)
				(justify left bottom mirror)
			)
		)
		(property "Description" "Net tie, 2 pins"
			(at 0 0 180)
			(layer "F.Fab")
			(hide yes)
			(effects
				(font
					(size 1.27 1.27)
					(thickness 0.15)
				)
			)
		)
		(property "Author" "Antmicro"
			(at 380.180002 225.76 0)
			(layer "B.Fab")
			(hide yes)
			(effects
				(font
					(size 1 1)
					(thickness 0.15)
				)
				(justify mirror)
			)
		)
		(property "License" "Apache-2.0"
			(at 380.180002 225.76 0)
			(layer "B.Fab")
			(hide yes)
			(effects
				(font
					(size 1 1)
					(thickness 0.15)
				)
				(justify mirror)
			)
		)
		(property "MPN" ""
			(at 380.180002 225.76 0)
			(layer "B.Fab")
			(hide yes)
			(effects
				(font
					(size 1 1)
					(thickness 0.15)
				)
				(justify mirror)
			)
		)
		(property "Manufacturer" ""
			(at 380.180002 225.76 0)
			(layer "B.Fab")
			(hide yes)
			(effects
				(font
					(size 1 1)
					(thickness 0.15)
				)
				(justify mirror)
			)
		)
		(sheetname "DC-DC Converters")
		(sheetfile "dc-dc.kicad_sch")
		(attr exclude_from_pos_files)
		(net_tie_pad_groups "1, 2")
		(fp_poly
			(pts
				(xy -0.0635 0.0635) (xy 0.0625 0.0635) (xy 0.0625 -0.0635) (xy -0.0635 -0.0635)
			)
			(stroke
				(width 0)
				(type solid)
			)
			(fill yes)
			(layer "B.Cu")
		)
		(pad "1" smd roundrect
			(at -0.127 0)
			(size 0.127 0.127)
			(layers "B.Cu")
			(roundrect_rratio 0.5)
			(chamfer_ratio 0)
			(chamfer top_left bottom_left)
			(net 1 "GND")
			(pinfunction "1")
			(pintype "passive")
		)
		(pad "2" smd roundrect
			(at 0.126 0 180)
			(size 0.127 0.127)
			(layers "B.Cu")
			(roundrect_rratio 0.5)
			(chamfer_ratio 0)
			(chamfer top_left bottom_left)
			(net 1222 "/DC-DC Converters/SENSE_1V0_N")
			(pinfunction "2")
			(pintype "passive")
		)
	)
	(footprint "antmicro-footprints:USON-10_2.5x1mm_P0.5mm"
		(layer "B.Cu")
		(at 257.251 107.625 90)
		(descr "USON-10 2.5x1mm_ Pitch 0.5mm")
		(tags "USON-10 2.5x1mm Pitch 0.5mm")
		(property "Reference" "U28"
			(at 0.875 1.024 0)
			(layer "B.SilkS")
			(effects
				(font
					(size 0.7 0.7)
					(thickness 0.15)
				)
				(justify left bottom mirror)
			)
		)
		(property "Value" "TPD4E05U06QDQARQ1"
			(at 0.018 -2.499 270)
			(layer "B.Fab")
			(effects
				(font
					(size 0.7 0.7)
					(thickness 0.15)
				)
				(justify left bottom mirror)
			)
		)
		(property "Description" "ESD protection"
			(at 0 0 90)
			(layer "F.Fab")
			(hide yes)
			(effects
				(font
					(size 1.27 1.27)
					(thickness 0.15)
				)
			)
		)
		(property "Author" "Antmicro"
			(at 364.876 -149.626 0)
			(layer "B.Fab")
			(hide yes)
			(effects
				(font
					(size 1 1)
					(thickness 0.15)
				)
				(justify mirror)
			)
		)
		(property "License" "Apache-2.0"
			(at 364.876 -149.626 0)
			(layer "B.Fab")
			(hide yes)
			(effects
				(font
					(size 1 1)
					(thickness 0.15)
				)
				(justify mirror)
			)
		)
		(property "MPN" "TPD4E05U06QDQARQ1"
			(at 364.876 -149.626 0)
			(layer "B.Fab")
			(hide yes)
			(effects
				(font
					(size 1 1)
					(thickness 0.15)
				)
				(justify mirror)
			)
		)
		(property "Manufacturer" "Texas Instruments"
			(at 364.876 -149.626 0)
			(layer "B.Fab")
			(hide yes)
			(effects
				(font
					(size 1 1)
					(thickness 0.15)
				)
				(justify mirror)
			)
		)
		(sheetname "HDMI + Ethernet")
		(sheetfile "hdmi-ethernet.kicad_sch")
		(attr smd)
		(fp_line
			(start 0.498 -1.398)
			(end -0.5 -1.398)
			(stroke
				(width 0.15)
				(type solid)
			)
			(layer "B.SilkS")
		)
		(fp_line
			(start 0.498 1.401)
			(end -0.5 1.401)
			(stroke
				(width 0.15)
				(type solid)
			)
			(layer "B.SilkS")
		)
		(fp_circle
			(center -0.68 1.27)
			(end -0.63 1.27)
			(stroke
				(width 0.15)
				(type solid)
			)
			(fill yes)
			(layer "B.SilkS")
		)
		(fp_rect
			(start -0.8 1.5)
			(end 0.8 -1.499)
			(stroke
				(width 0.05)
				(type solid)
			)
			(fill no)
			(layer "B.CrtYd")
		)
		(fp_line
			(start -0.5 -1.249)
			(end 0.498 -1.249)
			(stroke
				(width 0.15)
				(type solid)
			)
			(layer "B.Fab")
		)
		(fp_line
			(start -0.5 1)
			(end -0.5 -1.249)
			(stroke
				(width 0.15)
				(type solid)
			)
			(layer "B.Fab")
		)
		(fp_line
			(start 0.498 1.25)
			(end 0.498 -1.249)
			(stroke
				(width 0.15)
				(type solid)
			)
			(layer "B.Fab")
		)
		(fp_line
			(start 0.498 1.25)
			(end -0.25 1.25)
			(stroke
				(width 0.15)
				(type solid)
			)
			(layer "B.Fab")
		)
		(fp_line
			(start -0.25 1.25)
			(end -0.5 1)
			(stroke
				(width 0.15)
				(type solid)
			)
			(layer "B.Fab")
		)
		(pad "1" smd roundrect
			(at -0.387 1 180)
			(size 0.25 0.55)
			(layers "B.Cu" "B.Mask" "B.Paste")
			(roundrect_rratio 0.25)
			(net 867 "/HDMI + Ethernet/HDMI_CONN_D2_P")
			(pintype "passive")
		)
		(pad "2" smd roundrect
			(at -0.387 0.5 180)
			(size 0.25 0.55)
			(layers "B.Cu" "B.Mask" "B.Paste")
			(roundrect_rratio 0.25)
			(net 866 "/HDMI + Ethernet/HDMI_CONN_D2_N")
			(pintype "passive")
		)
		(pad "3" smd roundrect
			(at -0.387 0 180)
			(size 0.4 0.55)
			(layers "B.Cu" "B.Mask" "B.Paste")
			(roundrect_rratio 0.25)
			(net 1 "GND")
			(pintype "power_in")
		)
		(pad "4" smd roundrect
			(at -0.387 -0.498 180)
			(size 0.25 0.55)
			(layers "B.Cu" "B.Mask" "B.Paste")
			(roundrect_rratio 0.25)
			(net 865 "/HDMI + Ethernet/HDMI_CONN_D1_P")
			(pintype "passive")
		)
		(pad "5" smd roundrect
			(at -0.387 -0.998 180)
			(size 0.25 0.55)
			(layers "B.Cu" "B.Mask" "B.Paste")
			(roundrect_rratio 0.25)
			(net 864 "/HDMI + Ethernet/HDMI_CONN_D1_N")
			(pintype "passive")
		)
		(pad "6" smd roundrect
			(at 0.385 -0.998 180)
			(size 0.25 0.55)
			(layers "B.Cu" "B.Mask" "B.Paste")
			(roundrect_rratio 0.25)
			(net 864 "/HDMI + Ethernet/HDMI_CONN_D1_N")
			(pintype "passive")
		)
		(pad "7" smd roundrect
			(at 0.385 -0.498 180)
			(size 0.25 0.55)
			(layers "B.Cu" "B.Mask" "B.Paste")
			(roundrect_rratio 0.25)
			(net 865 "/HDMI + Ethernet/HDMI_CONN_D1_P")
			(pintype "passive")
		)
		(pad "8" smd roundrect
			(at 0.385 0 180)
			(size 0.4 0.55)
			(layers "B.Cu" "B.Mask" "B.Paste")
			(roundrect_rratio 0.25)
			(net 1 "GND")
			(pintype "passive")
		)
		(pad "9" smd roundrect
			(at 0.385 0.5 180)
			(size 0.25 0.55)
			(layers "B.Cu" "B.Mask" "B.Paste")
			(roundrect_rratio 0.25)
			(net 866 "/HDMI + Ethernet/HDMI_CONN_D2_N")
			(pintype "passive")
		)
		(pad "10" smd roundrect
			(at 0.385 1 180)
			(size 0.25 0.55)
			(layers "B.Cu" "B.Mask" "B.Paste")
			(roundrect_rratio 0.25)
			(net 867 "/HDMI + Ethernet/HDMI_CONN_D2_P")
			(pintype "passive")
		)
	)
)
